#ISCELL
  mstr_misc dns *
  *
#ISCELL
  mstr_misc prelim *
  *
#ISCELL
  mstr_symbols design_note *
  *
#ISCELL
  mstr_symbols intel_corp_bpage *
  *
#ISCELL
  mstr_symbols pvccin_cpu1 *
  page71_i35
#ISCELL
  mstr_symbols pvccin_cpu1 *
  page71_i36
#ISCELL
  mstr_standard offpage *
  page71_i38
#ISCELL
  mstr_standard offpage *
  page71_i39
#ISCELL
  mstr_symbols pvccin_cpu1 *
  page71_i40
#ISCELL
  mstr_symbols pvccin_cpu1 *
  page71_i41
#ISCELL
  mstr_symbols gnd *
  page71_i42
#CELL
  mstr_discrete res *
  page71_i43
#ISCELL
  mstr_symbols pvccin_cpu1 *
  page71_i45
#CELL
  mstr_discrete res *
  page71_i49
#CELL
  chpset_lib skx_ext_b *
  page71_i50
#CELL
  chpset_lib skx_ext_b *
  page71_i51
#ISCELL
  mstr_symbols pvccio_cpu1 *
  page71_i52
#CELL
  mstr_discrete res *
  page71_i53
